(kicad_pcb
	(version 20260206)
	(generator "pcbnew")
	(generator_version "10.0")
	(general
		(thickness 1.6)
		(legacy_teardrops no)
	)
	(paper "A4")
	(title_block
		(title "03242023_DA0F0TMBIJ0_F0T_Motherboard_J_brd_V01_OCP.brd")
		(comment 1 "Grand Teton / footprint 2048 of 6105 (J3), pads 113-224 of 291")
	)
	(layers
		(0 "F.Cu" signal "TOP")
		(4 "In1.Cu" signal "GND")
		(6 "In2.Cu" signal "IN1")
		(8 "In3.Cu" signal "GND1")
		(10 "In4.Cu" signal "IN2")
		(12 "In5.Cu" signal "GND2")
		(14 "In6.Cu" signal "IN3")
		(16 "In7.Cu" signal "GND3")
		(18 "In8.Cu" signal "VCC")
		(20 "In9.Cu" signal "VCC1")
		(22 "In10.Cu" signal "GND4")
		(24 "In11.Cu" signal "IN4")
		(26 "In12.Cu" signal "GND5")
		(28 "In13.Cu" signal "IN5")
		(30 "In14.Cu" signal "GND6")
		(32 "In15.Cu" signal "IN6")
		(34 "In16.Cu" signal "GND7")
		(2 "B.Cu" signal "BOTTOM")
		(9 "F.Adhes" user "F.Adhesive")
		(11 "B.Adhes" user "B.Adhesive")
		(13 "F.Paste" user "Package Geometry/Pastemask Top")
		(15 "B.Paste" user "Package Geometry/Pastemask Bottom")
		(5 "F.SilkS" user "Ref Des/Silkscreen Top")
		(7 "B.SilkS" user "Ref Des/Silkscreen Bottom")
		(1 "F.Mask" user "Board Geometry/Soldermask Top")
		(3 "B.Mask" user "Board Geometry/Soldermask Bottom")
		(17 "Dwgs.User" user "User.Drawings")
		(19 "Cmts.User" user "User.Comments")
		(21 "Eco1.User" user "User.Eco1")
		(23 "Eco2.User" user "User.Eco2")
		(25 "Edge.Cuts" user "Board Geometry/Outline")
		(27 "Margin" user)
		(31 "F.CrtYd" user "Package Geometry/Place Bound Top")
		(29 "B.CrtYd" user "Package Geometry/Place Bound Bottom")
		(35 "F.Fab" user "Ref Des/Assembly Top")
		(33 "B.Fab" user "Ref Des/Assembly Bottom")
	)
	(footprint ""
		(layer "F.Cu")
		(at 288.305748 -258.091686)
		(property "Reference" "J3"
			(at -3.683 -81.702148 0)
			(unlocked yes)
			(layer "F.SilkS")
			(effects
				(font
					(size 0.7874 0.5842)
					(thickness 0.1524)
				)
				(justify left)
			)
		)
		(property "Value" ""
			(at 0 0 0)
			(layer "F.Fab")
			(effects
				(font
					(size 1.27 1.27)
				)
			)
		)
		(duplicate_pad_numbers_are_jumpers no)
		(pad "113" smd rect
			(at -2.050034 36.975034 270)
			(size 0.519938 1.4986)
			(layers "F.Cu" "F.Mask" "F.Paste")
			(net "M_B_CPU0_SB_DQ<9>")
		)
		(pad "114" smd rect
			(at -2.050034 37.824918 270)
			(size 0.519938 1.4986)
			(layers "F.Cu" "F.Mask" "F.Paste")
			(net "GND")
		)
		(pad "115" smd rect
			(at -2.050034 38.675056 270)
			(size 0.519938 1.4986)
			(layers "F.Cu" "F.Mask" "F.Paste")
			(net "M_B_CPU0_SB_DQS_DP<1>")
		)
		(pad "116" smd rect
			(at -2.050034 39.52494 270)
			(size 0.519938 1.4986)
			(layers "F.Cu" "F.Mask" "F.Paste")
			(net "M_B_CPU0_SB_DQS_DN<1>")
		)
		(pad "117" smd rect
			(at -2.050034 40.375078 270)
			(size 0.519938 1.4986)
			(layers "F.Cu" "F.Mask" "F.Paste")
			(net "GND")
		)
		(pad "118" smd rect
			(at -2.050034 41.224962 270)
			(size 0.519938 1.4986)
			(layers "F.Cu" "F.Mask" "F.Paste")
			(net "M_B_CPU0_SB_DQ<12>")
		)
		(pad "119" smd rect
			(at -2.050034 42.0751 270)
			(size 0.519938 1.4986)
			(layers "F.Cu" "F.Mask" "F.Paste")
			(net "GND")
		)
		(pad "120" smd rect
			(at -2.050034 42.924984 270)
			(size 0.519938 1.4986)
			(layers "F.Cu" "F.Mask" "F.Paste")
			(net "M_B_CPU0_SB_DQ<13>")
		)
		(pad "121" smd rect
			(at -2.050034 43.775122 270)
			(size 0.519938 1.4986)
			(layers "F.Cu" "F.Mask" "F.Paste")
			(net "GND")
		)
		(pad "122" smd rect
			(at -2.050034 44.625006 270)
			(size 0.519938 1.4986)
			(layers "F.Cu" "F.Mask" "F.Paste")
			(net "M_B_CPU0_SB_DQ<16>")
		)
		(pad "123" smd rect
			(at -2.050034 45.47489 270)
			(size 0.519938 1.4986)
			(layers "F.Cu" "F.Mask" "F.Paste")
			(net "GND")
		)
		(pad "124" smd rect
			(at -2.050034 46.325028 270)
			(size 0.519938 1.4986)
			(layers "F.Cu" "F.Mask" "F.Paste")
			(net "M_B_CPU0_SB_DQ<17>")
		)
		(pad "125" smd rect
			(at -2.050034 47.174912 270)
			(size 0.519938 1.4986)
			(layers "F.Cu" "F.Mask" "F.Paste")
			(net "GND")
		)
		(pad "126" smd rect
			(at -2.050034 48.02505 270)
			(size 0.519938 1.4986)
			(layers "F.Cu" "F.Mask" "F.Paste")
			(net "M_B_CPU0_SB_DQS_DP<2>")
		)
		(pad "127" smd rect
			(at -2.050034 48.874934 270)
			(size 0.519938 1.4986)
			(layers "F.Cu" "F.Mask" "F.Paste")
			(net "M_B_CPU0_SB_DQS_DN<2>")
		)
		(pad "128" smd rect
			(at -2.050034 49.725072 270)
			(size 0.519938 1.4986)
			(layers "F.Cu" "F.Mask" "F.Paste")
			(net "GND")
		)
		(pad "129" smd rect
			(at -2.050034 50.574956 270)
			(size 0.519938 1.4986)
			(layers "F.Cu" "F.Mask" "F.Paste")
			(net "M_B_CPU0_SB_DQ<20>")
		)
		(pad "130" smd rect
			(at -2.050034 51.425094 270)
			(size 0.519938 1.4986)
			(layers "F.Cu" "F.Mask" "F.Paste")
			(net "GND")
		)
		(pad "131" smd rect
			(at -2.050034 52.274978 270)
			(size 0.519938 1.4986)
			(layers "F.Cu" "F.Mask" "F.Paste")
			(net "M_B_CPU0_SB_DQ<21>")
		)
		(pad "132" smd rect
			(at -2.050034 53.125116 270)
			(size 0.519938 1.4986)
			(layers "F.Cu" "F.Mask" "F.Paste")
			(net "GND")
		)
		(pad "133" smd rect
			(at -2.050034 53.975 270)
			(size 0.519938 1.4986)
			(layers "F.Cu" "F.Mask" "F.Paste")
			(net "M_B_CPU0_SB_DQ<24>")
		)
		(pad "134" smd rect
			(at -2.050034 54.824884 270)
			(size 0.519938 1.4986)
			(layers "F.Cu" "F.Mask" "F.Paste")
			(net "GND")
		)
		(pad "135" smd rect
			(at -2.050034 55.675022 270)
			(size 0.519938 1.4986)
			(layers "F.Cu" "F.Mask" "F.Paste")
			(net "M_B_CPU0_SB_DQ<25>")
		)
		(pad "136" smd rect
			(at -2.050034 56.524906 270)
			(size 0.519938 1.4986)
			(layers "F.Cu" "F.Mask" "F.Paste")
			(net "GND")
		)
		(pad "137" smd rect
			(at -2.050034 57.375044 270)
			(size 0.519938 1.4986)
			(layers "F.Cu" "F.Mask" "F.Paste")
			(net "M_B_CPU0_SB_DQS_DP<3>")
		)
		(pad "138" smd rect
			(at -2.050034 58.224928 270)
			(size 0.519938 1.4986)
			(layers "F.Cu" "F.Mask" "F.Paste")
			(net "M_B_CPU0_SB_DQS_DN<3>")
		)
		(pad "139" smd rect
			(at -2.050034 59.075066 270)
			(size 0.519938 1.4986)
			(layers "F.Cu" "F.Mask" "F.Paste")
			(net "GND")
		)
		(pad "140" smd rect
			(at -2.050034 59.92495 270)
			(size 0.519938 1.4986)
			(layers "F.Cu" "F.Mask" "F.Paste")
			(net "M_B_CPU0_SB_DQ<28>")
		)
		(pad "141" smd rect
			(at -2.050034 60.775088 270)
			(size 0.519938 1.4986)
			(layers "F.Cu" "F.Mask" "F.Paste")
			(net "GND")
		)
		(pad "142" smd rect
			(at -2.050034 61.624972 270)
			(size 0.519938 1.4986)
			(layers "F.Cu" "F.Mask" "F.Paste")
			(net "M_B_CPU0_SB_DQ<29>")
		)
		(pad "143" smd rect
			(at -2.050034 62.47511 270)
			(size 0.519938 1.4986)
			(layers "F.Cu" "F.Mask" "F.Paste")
			(net "GND")
		)
		(pad "144" smd rect
			(at -2.050034 63.324994 270)
			(size 0.519938 1.4986)
			(layers "F.Cu" "F.Mask" "F.Paste")
			(net "TP_CHB_CPU0_DIMM1_FRU_1")
		)
		(pad "145" smd rect
			(at 2.050034 -63.324994 270)
			(size 0.519938 1.4986)
			(layers "F.Cu" "F.Mask" "F.Paste")
			(net "P12V_S3_AUX_CPU0_NVDIMM")
		)
		(pad "146" smd rect
			(at 2.050034 -62.47511 270)
			(size 0.519938 1.4986)
			(layers "F.Cu" "F.Mask" "F.Paste")
			(net "P12V_S3_AUX_CPU0_NVDIMM")
		)
		(pad "147" smd rect
			(at 2.050034 -61.624972 270)
			(size 0.519938 1.4986)
			(layers "F.Cu" "F.Mask" "F.Paste")
			(net "PWRGD_CHB_CPU0_DIMM1")
		)
		(pad "148" smd rect
			(at 2.050034 -60.775088 270)
			(size 0.519938 1.4986)
			(layers "F.Cu" "F.Mask" "F.Paste")
			(net "PD_CHB_CPU0_DIMM1_SAA")
		)
		(pad "149" smd rect
			(at 2.050034 -59.92495 270)
			(size 0.519938 1.4986)
			(layers "F.Cu" "F.Mask" "F.Paste")
			(net "TP_CHB_CPU0_DIMM1_FRU_2")
		)
		(pad "150" smd rect
			(at 2.050034 -59.075066 270)
			(size 0.519938 1.4986)
			(layers "F.Cu" "F.Mask" "F.Paste")
			(net "TP_CHB_CPU0_DIMM1_FRU_3")
		)
		(pad "151" smd rect
			(at 2.050034 -58.224928 270)
			(size 0.519938 1.4986)
			(layers "F.Cu" "F.Mask" "F.Paste")
			(net "GND")
		)
		(pad "152" smd rect
			(at 2.050034 -57.375044 270)
			(size 0.519938 1.4986)
			(layers "F.Cu" "F.Mask" "F.Paste")
			(net "M_B_CPU0_SA_DQ<2>")
		)
		(pad "153" smd rect
			(at 2.050034 -56.524906 270)
			(size 0.519938 1.4986)
			(layers "F.Cu" "F.Mask" "F.Paste")
			(net "GND")
		)
		(pad "154" smd rect
			(at 2.050034 -55.675022 270)
			(size 0.519938 1.4986)
			(layers "F.Cu" "F.Mask" "F.Paste")
			(net "M_B_CPU0_SA_DQ<3>")
		)
		(pad "155" smd rect
			(at 2.050034 -54.824884 270)
			(size 0.519938 1.4986)
			(layers "F.Cu" "F.Mask" "F.Paste")
			(net "GND")
		)
		(pad "156" smd rect
			(at 2.050034 -53.975 270)
			(size 0.519938 1.4986)
			(layers "F.Cu" "F.Mask" "F.Paste")
			(net "M_B_CPU0_SA_DQS_DN<5>")
		)
		(pad "157" smd rect
			(at 2.050034 -53.125116 270)
			(size 0.519938 1.4986)
			(layers "F.Cu" "F.Mask" "F.Paste")
			(net "M_B_CPU0_SA_DQS_DP<5>")
		)
		(pad "158" smd rect
			(at 2.050034 -52.274978 270)
			(size 0.519938 1.4986)
			(layers "F.Cu" "F.Mask" "F.Paste")
			(net "GND")
		)
		(pad "159" smd rect
			(at 2.050034 -51.425094 270)
			(size 0.519938 1.4986)
			(layers "F.Cu" "F.Mask" "F.Paste")
			(net "M_B_CPU0_SA_DQ<6>")
		)
		(pad "160" smd rect
			(at 2.050034 -50.574956 270)
			(size 0.519938 1.4986)
			(layers "F.Cu" "F.Mask" "F.Paste")
			(net "GND")
		)
		(pad "161" smd rect
			(at 2.050034 -49.725072 270)
			(size 0.519938 1.4986)
			(layers "F.Cu" "F.Mask" "F.Paste")
			(net "M_B_CPU0_SA_DQ<7>")
		)
		(pad "162" smd rect
			(at 2.050034 -48.874934 270)
			(size 0.519938 1.4986)
			(layers "F.Cu" "F.Mask" "F.Paste")
			(net "GND")
		)
		(pad "163" smd rect
			(at 2.050034 -48.02505 270)
			(size 0.519938 1.4986)
			(layers "F.Cu" "F.Mask" "F.Paste")
			(net "M_B_CPU0_SA_DQ<10>")
		)
		(pad "164" smd rect
			(at 2.050034 -47.174912 270)
			(size 0.519938 1.4986)
			(layers "F.Cu" "F.Mask" "F.Paste")
			(net "GND")
		)
		(pad "165" smd rect
			(at 2.050034 -46.325028 270)
			(size 0.519938 1.4986)
			(layers "F.Cu" "F.Mask" "F.Paste")
			(net "M_B_CPU0_SA_DQ<11>")
		)
		(pad "166" smd rect
			(at 2.050034 -45.47489 270)
			(size 0.519938 1.4986)
			(layers "F.Cu" "F.Mask" "F.Paste")
			(net "GND")
		)
		(pad "167" smd rect
			(at 2.050034 -44.625006 270)
			(size 0.519938 1.4986)
			(layers "F.Cu" "F.Mask" "F.Paste")
			(net "M_B_CPU0_SA_DQS_DN<6>")
		)
		(pad "168" smd rect
			(at 2.050034 -43.775122 270)
			(size 0.519938 1.4986)
			(layers "F.Cu" "F.Mask" "F.Paste")
			(net "M_B_CPU0_SA_DQS_DP<6>")
		)
		(pad "169" smd rect
			(at 2.050034 -42.924984 270)
			(size 0.519938 1.4986)
			(layers "F.Cu" "F.Mask" "F.Paste")
			(net "GND")
		)
		(pad "170" smd rect
			(at 2.050034 -42.0751 270)
			(size 0.519938 1.4986)
			(layers "F.Cu" "F.Mask" "F.Paste")
			(net "M_B_CPU0_SA_DQ<14>")
		)
		(pad "171" smd rect
			(at 2.050034 -41.224962 270)
			(size 0.519938 1.4986)
			(layers "F.Cu" "F.Mask" "F.Paste")
			(net "GND")
		)
		(pad "172" smd rect
			(at 2.050034 -40.375078 270)
			(size 0.519938 1.4986)
			(layers "F.Cu" "F.Mask" "F.Paste")
			(net "M_B_CPU0_SA_DQ<15>")
		)
		(pad "173" smd rect
			(at 2.050034 -39.52494 270)
			(size 0.519938 1.4986)
			(layers "F.Cu" "F.Mask" "F.Paste")
			(net "GND")
		)
		(pad "174" smd rect
			(at 2.050034 -38.675056 270)
			(size 0.519938 1.4986)
			(layers "F.Cu" "F.Mask" "F.Paste")
			(net "M_B_CPU0_SA_DQ<18>")
		)
		(pad "175" smd rect
			(at 2.050034 -37.824918 270)
			(size 0.519938 1.4986)
			(layers "F.Cu" "F.Mask" "F.Paste")
			(net "GND")
		)
		(pad "176" smd rect
			(at 2.050034 -36.975034 270)
			(size 0.519938 1.4986)
			(layers "F.Cu" "F.Mask" "F.Paste")
			(net "M_B_CPU0_SA_DQ<19>")
		)
		(pad "177" smd rect
			(at 2.050034 -36.124896 270)
			(size 0.519938 1.4986)
			(layers "F.Cu" "F.Mask" "F.Paste")
			(net "GND")
		)
		(pad "178" smd rect
			(at 2.050034 -35.275012 270)
			(size 0.519938 1.4986)
			(layers "F.Cu" "F.Mask" "F.Paste")
			(net "M_B_CPU0_SA_DQS_DN<7>")
		)
		(pad "179" smd rect
			(at 2.050034 -34.425128 270)
			(size 0.519938 1.4986)
			(layers "F.Cu" "F.Mask" "F.Paste")
			(net "M_B_CPU0_SA_DQS_DP<7>")
		)
		(pad "180" smd rect
			(at 2.050034 -33.57499 270)
			(size 0.519938 1.4986)
			(layers "F.Cu" "F.Mask" "F.Paste")
			(net "GND")
		)
		(pad "181" smd rect
			(at 2.050034 -32.725106 270)
			(size 0.519938 1.4986)
			(layers "F.Cu" "F.Mask" "F.Paste")
			(net "M_B_CPU0_SA_DQ<22>")
		)
		(pad "182" smd rect
			(at 2.050034 -31.874968 270)
			(size 0.519938 1.4986)
			(layers "F.Cu" "F.Mask" "F.Paste")
			(net "GND")
		)
		(pad "183" smd rect
			(at 2.050034 -31.025084 270)
			(size 0.519938 1.4986)
			(layers "F.Cu" "F.Mask" "F.Paste")
			(net "M_B_CPU0_SA_DQ<23>")
		)
		(pad "184" smd rect
			(at 2.050034 -30.174946 270)
			(size 0.519938 1.4986)
			(layers "F.Cu" "F.Mask" "F.Paste")
			(net "GND")
		)
		(pad "185" smd rect
			(at 2.050034 -29.325062 270)
			(size 0.519938 1.4986)
			(layers "F.Cu" "F.Mask" "F.Paste")
			(net "M_B_CPU0_SA_DQ<26>")
		)
		(pad "186" smd rect
			(at 2.050034 -28.474924 270)
			(size 0.519938 1.4986)
			(layers "F.Cu" "F.Mask" "F.Paste")
			(net "GND")
		)
		(pad "187" smd rect
			(at 2.050034 -27.62504 270)
			(size 0.519938 1.4986)
			(layers "F.Cu" "F.Mask" "F.Paste")
			(net "M_B_CPU0_SA_DQ<27>")
		)
		(pad "188" smd rect
			(at 2.050034 -26.774902 270)
			(size 0.519938 1.4986)
			(layers "F.Cu" "F.Mask" "F.Paste")
			(net "GND")
		)
		(pad "189" smd rect
			(at 2.050034 -25.925018 270)
			(size 0.519938 1.4986)
			(layers "F.Cu" "F.Mask" "F.Paste")
			(net "M_B_CPU0_SA_DQS_DN<8>")
		)
		(pad "190" smd rect
			(at 2.050034 -25.07488 270)
			(size 0.519938 1.4986)
			(layers "F.Cu" "F.Mask" "F.Paste")
			(net "M_B_CPU0_SA_DQS_DP<8>")
		)
		(pad "191" smd rect
			(at 2.050034 -24.224996 270)
			(size 0.519938 1.4986)
			(layers "F.Cu" "F.Mask" "F.Paste")
			(net "GND")
		)
		(pad "192" smd rect
			(at 2.050034 -23.375112 270)
			(size 0.519938 1.4986)
			(layers "F.Cu" "F.Mask" "F.Paste")
			(net "M_B_CPU0_SA_DQ<30>")
		)
		(pad "193" smd rect
			(at 2.050034 -22.524974 270)
			(size 0.519938 1.4986)
			(layers "F.Cu" "F.Mask" "F.Paste")
			(net "GND")
		)
		(pad "194" smd rect
			(at 2.050034 -21.67509 270)
			(size 0.519938 1.4986)
			(layers "F.Cu" "F.Mask" "F.Paste")
			(net "M_B_CPU0_SA_DQ<31>")
		)
		(pad "195" smd rect
			(at 2.050034 -20.824952 270)
			(size 0.519938 1.4986)
			(layers "F.Cu" "F.Mask" "F.Paste")
			(net "GND")
		)
		(pad "196" smd rect
			(at 2.050034 -19.975068 270)
			(size 0.519938 1.4986)
			(layers "F.Cu" "F.Mask" "F.Paste")
			(net "M_B_CPU0_SA_CB<2>")
		)
		(pad "197" smd rect
			(at 2.050034 -19.12493 270)
			(size 0.519938 1.4986)
			(layers "F.Cu" "F.Mask" "F.Paste")
			(net "GND")
		)
		(pad "198" smd rect
			(at 2.050034 -18.275046 270)
			(size 0.519938 1.4986)
			(layers "F.Cu" "F.Mask" "F.Paste")
			(net "M_B_CPU0_SA_CB<3>")
		)
		(pad "199" smd rect
			(at 2.050034 -17.424908 270)
			(size 0.519938 1.4986)
			(layers "F.Cu" "F.Mask" "F.Paste")
			(net "GND")
		)
		(pad "200" smd rect
			(at 2.050034 -16.575024 270)
			(size 0.519938 1.4986)
			(layers "F.Cu" "F.Mask" "F.Paste")
			(net "M_B_CPU0_SA_DQS_DN<9>")
		)
		(pad "201" smd rect
			(at 2.050034 -15.724886 270)
			(size 0.519938 1.4986)
			(layers "F.Cu" "F.Mask" "F.Paste")
			(net "M_B_CPU0_SA_DQS_DP<9>")
		)
		(pad "202" smd rect
			(at 2.050034 -14.875002 270)
			(size 0.519938 1.4986)
			(layers "F.Cu" "F.Mask" "F.Paste")
			(net "GND")
		)
		(pad "203" smd rect
			(at 2.050034 -14.025118 270)
			(size 0.519938 1.4986)
			(layers "F.Cu" "F.Mask" "F.Paste")
			(net "M_B_CPU0_SA_CB<6>")
		)
		(pad "204" smd rect
			(at 2.050034 -13.17498 270)
			(size 0.519938 1.4986)
			(layers "F.Cu" "F.Mask" "F.Paste")
			(net "GND")
		)
		(pad "205" smd rect
			(at 2.050034 -12.325096 270)
			(size 0.519938 1.4986)
			(layers "F.Cu" "F.Mask" "F.Paste")
			(net "M_B_CPU0_SA_CB<7>")
		)
		(pad "206" smd rect
			(at 2.050034 -11.474958 270)
			(size 0.519938 1.4986)
			(layers "F.Cu" "F.Mask" "F.Paste")
			(net "GND")
		)
		(pad "207" smd rect
			(at 2.050034 -10.625074 270)
			(size 0.519938 1.4986)
			(layers "F.Cu" "F.Mask" "F.Paste")
			(net "RST_M_AB_CPU0_FPGA_N")
		)
		(pad "208" smd rect
			(at 2.050034 -9.774936 270)
			(size 0.519938 1.4986)
			(layers "F.Cu" "F.Mask" "F.Paste")
			(net "GND")
		)
		(pad "209" smd rect
			(at 2.050034 -8.925052 270)
			(size 0.519938 1.4986)
			(layers "F.Cu" "F.Mask" "F.Paste")
			(net "M_B_CPU0_SA_CS_N<1>")
		)
		(pad "210" smd rect
			(at 2.050034 -8.074914 270)
			(size 0.519938 1.4986)
			(layers "F.Cu" "F.Mask" "F.Paste")
			(net "GND")
		)
		(pad "211" smd rect
			(at 2.050034 -7.22503 270)
			(size 0.519938 1.4986)
			(layers "F.Cu" "F.Mask" "F.Paste")
			(net "M_B_CPU0_SA_CA<1>")
		)
		(pad "212" smd rect
			(at 2.050034 -6.374892 270)
			(size 0.519938 1.4986)
			(layers "F.Cu" "F.Mask" "F.Paste")
			(net "GND")
		)
		(pad "213" smd rect
			(at 2.050034 -5.525008 270)
			(size 0.519938 1.4986)
			(layers "F.Cu" "F.Mask" "F.Paste")
			(net "M_B_CPU0_SA_CA<3>")
		)
		(pad "214" smd rect
			(at 2.050034 -4.675124 270)
			(size 0.519938 1.4986)
			(layers "F.Cu" "F.Mask" "F.Paste")
			(net "GND")
		)
		(pad "215" smd rect
			(at 2.050034 -3.824986 270)
			(size 0.519938 1.4986)
			(layers "F.Cu" "F.Mask" "F.Paste")
			(net "M_B_CPU0_SA_CA<5>")
		)
		(pad "216" smd rect
			(at 2.050034 -2.975102 270)
			(size 0.519938 1.4986)
			(layers "F.Cu" "F.Mask" "F.Paste")
			(net "GND")
		)
		(pad "217" smd rect
			(at 2.050034 -2.124964 270)
			(size 0.519938 1.4986)
			(layers "F.Cu" "F.Mask" "F.Paste")
			(net "M_B_CPU0_CLK_DP<0>")
		)
		(pad "218" smd rect
			(at 2.050034 -1.27508 270)
			(size 0.519938 1.4986)
			(layers "F.Cu" "F.Mask" "F.Paste")
			(net "M_B_CPU0_CLK_DN<0>")
		)
		(pad "219" smd rect
			(at 2.050034 -0.424942 270)
			(size 0.519938 1.4986)
			(layers "F.Cu" "F.Mask" "F.Paste")
			(net "GND")
		)
		(pad "220" smd rect
			(at 2.050034 5.525008 270)
			(size 0.519938 1.4986)
			(layers "F.Cu" "F.Mask" "F.Paste")
			(net "TP_CHB_CPU0_DIMM1_FRU_4")
		)
		(pad "221" smd rect
			(at 2.050034 6.374892 270)
			(size 0.519938 1.4986)
			(layers "F.Cu" "F.Mask" "F.Paste")
			(net "M_B_CPU0_SB_CA<1>")
		)
		(pad "222" smd rect
			(at 2.050034 7.22503 270)
			(size 0.519938 1.4986)
			(layers "F.Cu" "F.Mask" "F.Paste")
			(net "GND")
		)
		(pad "223" smd rect
			(at 2.050034 8.074914 270)
			(size 0.519938 1.4986)
			(layers "F.Cu" "F.Mask" "F.Paste")
			(net "M_B_CPU0_SB_CA<3>")
		)
		(pad "224" smd rect
			(at 2.050034 8.925052 270)
			(size 0.519938 1.4986)
			(layers "F.Cu" "F.Mask" "F.Paste")
			(net "GND")
		)
	)
)
